(kicad_pcb
	(version 20260206)
	(generator "pcbnew")
	(generator_version "10.0")
	(general
		(thickness 1.6)
		(legacy_teardrops no)
	)
	(paper "A4")
	(title_block
		(title "12092022_DA0F0TFB6D0_F0T_FAN_BOARD_MP5048_D_brd_v02_OCP.brd")
		(comment 1 "Grand Teton / footprints 235-240 of 924")
	)
	(layers
		(0 "F.Cu" signal "TOP")
		(4 "In1.Cu" signal "GND")
		(6 "In2.Cu" signal "IN1")
		(8 "In3.Cu" signal "IN2")
		(10 "In4.Cu" signal "GND1")
		(2 "B.Cu" signal "BOTTOM")
		(9 "F.Adhes" user "F.Adhesive")
		(11 "B.Adhes" user "B.Adhesive")
		(13 "F.Paste" user "Package Geometry/Pastemask Top")
		(15 "B.Paste" user "Package Geometry/Pastemask Bottom")
		(5 "F.SilkS" user "Ref Des/Silkscreen Top")
		(7 "B.SilkS" user "Ref Des/Silkscreen Bottom")
		(1 "F.Mask" user "Board Geometry/Soldermask Top")
		(3 "B.Mask" user "Board Geometry/Soldermask Bottom")
		(17 "Dwgs.User" user "User.Drawings")
		(19 "Cmts.User" user "User.Comments")
		(21 "Eco1.User" user "User.Eco1")
		(23 "Eco2.User" user "User.Eco2")
		(25 "Edge.Cuts" user "Board Geometry/Outline")
		(27 "Margin" user)
		(31 "F.CrtYd" user "Package Geometry/Place Bound Top")
		(29 "B.CrtYd" user "Package Geometry/Place Bound Bottom")
		(35 "F.Fab" user "Ref Des/Assembly Top")
		(33 "B.Fab" user "Ref Des/Assembly Bottom")
	)
	(footprint ""
		(layer "F.Cu")
		(at 29.083 -21.209)
		(property "Reference" "R5519"
			(at 0 0 0)
			(layer "F.SilkS")
			(hide yes)
			(effects
				(font
					(size 1.27 1.27)
				)
			)
		)
		(property "Value" ""
			(at 0 0 0)
			(layer "F.Fab")
			(effects
				(font
					(size 1.27 1.27)
				)
			)
		)
		(duplicate_pad_numbers_are_jumpers no)
		(fp_line
			(start -0.7874 -0.4064)
			(end 0.7874 -0.4064)
			(stroke
				(width 0.1524)
				(type default)
			)
			(layer "F.SilkS")
		)
		(fp_line
			(start -0.7874 0.4064)
			(end -0.7874 -0.4064)
			(stroke
				(width 0.1524)
				(type default)
			)
			(layer "F.SilkS")
		)
		(fp_line
			(start 0.7874 -0.4064)
			(end 0.7874 0.4064)
			(stroke
				(width 0.1524)
				(type default)
			)
			(layer "F.SilkS")
		)
		(fp_line
			(start 0.7874 0.4064)
			(end -0.7874 0.4064)
			(stroke
				(width 0.1524)
				(type default)
			)
			(layer "F.SilkS")
		)
		(fp_line
			(start -0.67945 -0.305054)
			(end -0.12065 -0.305054)
			(stroke
				(width 0.1)
				(type default)
			)
			(layer "F.Fab")
		)
		(fp_line
			(start -0.67945 0.3048)
			(end -0.67945 -0.305054)
			(stroke
				(width 0.1)
				(type default)
			)
			(layer "F.Fab")
		)
		(fp_line
			(start -0.12065 -0.305054)
			(end -0.12065 -0.2794)
			(stroke
				(width 0.1)
				(type default)
			)
			(layer "F.Fab")
		)
		(fp_line
			(start -0.12065 -0.2794)
			(end 0.12065 -0.2794)
			(stroke
				(width 0.1)
				(type default)
			)
			(layer "F.Fab")
		)
		(fp_line
			(start -0.12065 0.2794)
			(end -0.12065 0.3048)
			(stroke
				(width 0.1)
				(type default)
			)
			(layer "F.Fab")
		)
		(fp_line
			(start -0.12065 0.3048)
			(end -0.67945 0.3048)
			(stroke
				(width 0.1)
				(type default)
			)
			(layer "F.Fab")
		)
		(fp_line
			(start 0.120396 0.2794)
			(end -0.12065 0.2794)
			(stroke
				(width 0.1)
				(type default)
			)
			(layer "F.Fab")
		)
		(fp_line
			(start 0.120396 0.3048)
			(end 0.120396 0.2794)
			(stroke
				(width 0.1)
				(type default)
			)
			(layer "F.Fab")
		)
		(fp_line
			(start 0.12065 -0.3048)
			(end 0.67945 -0.3048)
			(stroke
				(width 0.1)
				(type default)
			)
			(layer "F.Fab")
		)
		(fp_line
			(start 0.12065 -0.2794)
			(end 0.12065 -0.3048)
			(stroke
				(width 0.1)
				(type default)
			)
			(layer "F.Fab")
		)
		(fp_line
			(start 0.67945 -0.3048)
			(end 0.67945 0.3048)
			(stroke
				(width 0.1)
				(type default)
			)
			(layer "F.Fab")
		)
		(fp_line
			(start 0.67945 0.3048)
			(end 0.120396 0.3048)
			(stroke
				(width 0.1)
				(type default)
			)
			(layer "F.Fab")
		)
		(pad "1" smd circle
			(at -0.40005 0)
			(size 0 0)
			(layers "F.Cu" "F.Mask" "F.Paste")
			(net "P3V3_AUX")
		)
		(pad "2" smd circle
			(at 0.40005 0)
			(size 0 0)
			(layers "F.Cu" "F.Mask" "F.Paste")
			(net "FAN_4_PWM")
		)
	)
	(footprint ""
		(layer "F.Cu")
		(at 40.767 -73.152 180)
		(property "Reference" "PR35"
			(at 0 0 180)
			(layer "F.SilkS")
			(hide yes)
			(effects
				(font
					(size 1.27 1.27)
				)
			)
		)
		(property "Value" ""
			(at 0 0 180)
			(layer "F.Fab")
			(effects
				(font
					(size 1.27 1.27)
				)
			)
		)
		(duplicate_pad_numbers_are_jumpers no)
		(fp_line
			(start 0.7874 0.4064)
			(end -0.7874 0.4064)
			(stroke
				(width 0.1524)
				(type default)
			)
			(layer "F.SilkS")
		)
		(fp_line
			(start 0.7874 -0.4064)
			(end 0.7874 0.4064)
			(stroke
				(width 0.1524)
				(type default)
			)
			(layer "F.SilkS")
		)
		(fp_line
			(start -0.7874 0.4064)
			(end -0.7874 -0.4064)
			(stroke
				(width 0.1524)
				(type default)
			)
			(layer "F.SilkS")
		)
		(fp_line
			(start -0.7874 -0.4064)
			(end 0.7874 -0.4064)
			(stroke
				(width 0.1524)
				(type default)
			)
			(layer "F.SilkS")
		)
		(fp_line
			(start 0.67945 0.3048)
			(end 0.120396 0.3048)
			(stroke
				(width 0.1)
				(type default)
			)
			(layer "F.Fab")
		)
		(fp_line
			(start 0.67945 -0.3048)
			(end 0.67945 0.3048)
			(stroke
				(width 0.1)
				(type default)
			)
			(layer "F.Fab")
		)
		(fp_line
			(start 0.12065 -0.2794)
			(end 0.12065 -0.3048)
			(stroke
				(width 0.1)
				(type default)
			)
			(layer "F.Fab")
		)
		(fp_line
			(start 0.12065 -0.3048)
			(end 0.67945 -0.3048)
			(stroke
				(width 0.1)
				(type default)
			)
			(layer "F.Fab")
		)
		(fp_line
			(start 0.120396 0.3048)
			(end 0.120396 0.2794)
			(stroke
				(width 0.1)
				(type default)
			)
			(layer "F.Fab")
		)
		(fp_line
			(start 0.120396 0.2794)
			(end -0.12065 0.2794)
			(stroke
				(width 0.1)
				(type default)
			)
			(layer "F.Fab")
		)
		(fp_line
			(start -0.12065 0.3048)
			(end -0.67945 0.3048)
			(stroke
				(width 0.1)
				(type default)
			)
			(layer "F.Fab")
		)
		(fp_line
			(start -0.12065 0.2794)
			(end -0.12065 0.3048)
			(stroke
				(width 0.1)
				(type default)
			)
			(layer "F.Fab")
		)
		(fp_line
			(start -0.12065 -0.2794)
			(end 0.12065 -0.2794)
			(stroke
				(width 0.1)
				(type default)
			)
			(layer "F.Fab")
		)
		(fp_line
			(start -0.12065 -0.305054)
			(end -0.12065 -0.2794)
			(stroke
				(width 0.1)
				(type default)
			)
			(layer "F.Fab")
		)
		(fp_line
			(start -0.67945 0.3048)
			(end -0.67945 -0.305054)
			(stroke
				(width 0.1)
				(type default)
			)
			(layer "F.Fab")
		)
		(fp_line
			(start -0.67945 -0.305054)
			(end -0.12065 -0.305054)
			(stroke
				(width 0.1)
				(type default)
			)
			(layer "F.Fab")
		)
		(pad "1" smd circle
			(at -0.40005 0 180)
			(size 0 0)
			(layers "F.Cu" "F.Mask" "F.Paste")
			(net "FAN_2_FAULT_R")
		)
		(pad "2" smd circle
			(at 0.40005 0 180)
			(size 0 0)
			(layers "F.Cu" "F.Mask" "F.Paste")
			(net "FAN_2_P3V_R")
		)
	)
	(footprint ""
		(layer "F.Cu")
		(at 38.62705 -123.698)
		(property "Reference" "R5584"
			(at 0 0 0)
			(layer "F.SilkS")
			(hide yes)
			(effects
				(font
					(size 1.27 1.27)
				)
			)
		)
		(property "Value" ""
			(at 0 0 0)
			(layer "F.Fab")
			(effects
				(font
					(size 1.27 1.27)
				)
			)
		)
		(duplicate_pad_numbers_are_jumpers no)
		(fp_line
			(start -0.7874 -0.4064)
			(end 0.7874 -0.4064)
			(stroke
				(width 0.1524)
				(type default)
			)
			(layer "F.SilkS")
		)
		(fp_line
			(start -0.7874 0.4064)
			(end -0.7874 -0.4064)
			(stroke
				(width 0.1524)
				(type default)
			)
			(layer "F.SilkS")
		)
		(fp_line
			(start 0.7874 -0.4064)
			(end 0.7874 0.4064)
			(stroke
				(width 0.1524)
				(type default)
			)
			(layer "F.SilkS")
		)
		(fp_line
			(start 0.7874 0.4064)
			(end -0.7874 0.4064)
			(stroke
				(width 0.1524)
				(type default)
			)
			(layer "F.SilkS")
		)
		(fp_line
			(start -0.67945 -0.305054)
			(end -0.12065 -0.305054)
			(stroke
				(width 0.1)
				(type default)
			)
			(layer "F.Fab")
		)
		(fp_line
			(start -0.67945 0.3048)
			(end -0.67945 -0.305054)
			(stroke
				(width 0.1)
				(type default)
			)
			(layer "F.Fab")
		)
		(fp_line
			(start -0.12065 -0.305054)
			(end -0.12065 -0.2794)
			(stroke
				(width 0.1)
				(type default)
			)
			(layer "F.Fab")
		)
		(fp_line
			(start -0.12065 -0.2794)
			(end 0.12065 -0.2794)
			(stroke
				(width 0.1)
				(type default)
			)
			(layer "F.Fab")
		)
		(fp_line
			(start -0.12065 0.2794)
			(end -0.12065 0.3048)
			(stroke
				(width 0.1)
				(type default)
			)
			(layer "F.Fab")
		)
		(fp_line
			(start -0.12065 0.3048)
			(end -0.67945 0.3048)
			(stroke
				(width 0.1)
				(type default)
			)
			(layer "F.Fab")
		)
		(fp_line
			(start 0.120396 0.2794)
			(end -0.12065 0.2794)
			(stroke
				(width 0.1)
				(type default)
			)
			(layer "F.Fab")
		)
		(fp_line
			(start 0.120396 0.3048)
			(end 0.120396 0.2794)
			(stroke
				(width 0.1)
				(type default)
			)
			(layer "F.Fab")
		)
		(fp_line
			(start 0.12065 -0.3048)
			(end 0.67945 -0.3048)
			(stroke
				(width 0.1)
				(type default)
			)
			(layer "F.Fab")
		)
		(fp_line
			(start 0.12065 -0.2794)
			(end 0.12065 -0.3048)
			(stroke
				(width 0.1)
				(type default)
			)
			(layer "F.Fab")
		)
		(fp_line
			(start 0.67945 -0.3048)
			(end 0.67945 0.3048)
			(stroke
				(width 0.1)
				(type default)
			)
			(layer "F.Fab")
		)
		(fp_line
			(start 0.67945 0.3048)
			(end 0.120396 0.3048)
			(stroke
				(width 0.1)
				(type default)
			)
			(layer "F.Fab")
		)
		(pad "1" smd rect
			(at -0.40005 0 180)
			(size 0.4572 0.508)
			(layers "F.Cu" "F.Mask" "F.Paste")
			(net "FAN_3_TACH_OL")
		)
		(pad "2" smd rect
			(at 0.40005 0 180)
			(size 0.4572 0.508)
			(layers "F.Cu" "F.Mask" "F.Paste")
			(net "FAN_3_TACH_OL_R2")
		)
	)
	(footprint ""
		(layer "F.Cu")
		(at 32.258 -22.098 90)
		(property "Reference" "R5397"
			(at 0 0 90)
			(layer "F.SilkS")
			(hide yes)
			(effects
				(font
					(size 1.27 1.27)
				)
			)
		)
		(property "Value" ""
			(at 0 0 90)
			(layer "F.Fab")
			(effects
				(font
					(size 1.27 1.27)
				)
			)
		)
		(duplicate_pad_numbers_are_jumpers no)
		(fp_line
			(start 0.7874 -0.4064)
			(end 0.7874 0.4064)
			(stroke
				(width 0.1524)
				(type default)
			)
			(layer "F.SilkS")
		)
		(fp_line
			(start -0.7874 -0.4064)
			(end 0.7874 -0.4064)
			(stroke
				(width 0.1524)
				(type default)
			)
			(layer "F.SilkS")
		)
		(fp_line
			(start 0.7874 0.4064)
			(end -0.7874 0.4064)
			(stroke
				(width 0.1524)
				(type default)
			)
			(layer "F.SilkS")
		)
		(fp_line
			(start -0.7874 0.4064)
			(end -0.7874 -0.4064)
			(stroke
				(width 0.1524)
				(type default)
			)
			(layer "F.SilkS")
		)
		(fp_line
			(start -0.12065 -0.305054)
			(end -0.12065 -0.2794)
			(stroke
				(width 0.1)
				(type default)
			)
			(layer "F.Fab")
		)
		(fp_line
			(start -0.67945 -0.305054)
			(end -0.12065 -0.305054)
			(stroke
				(width 0.1)
				(type default)
			)
			(layer "F.Fab")
		)
		(fp_line
			(start 0.67945 -0.3048)
			(end 0.67945 0.3048)
			(stroke
				(width 0.1)
				(type default)
			)
			(layer "F.Fab")
		)
		(fp_line
			(start 0.12065 -0.3048)
			(end 0.67945 -0.3048)
			(stroke
				(width 0.1)
				(type default)
			)
			(layer "F.Fab")
		)
		(fp_line
			(start 0.12065 -0.2794)
			(end 0.12065 -0.3048)
			(stroke
				(width 0.1)
				(type default)
			)
			(layer "F.Fab")
		)
		(fp_line
			(start -0.12065 -0.2794)
			(end 0.12065 -0.2794)
			(stroke
				(width 0.1)
				(type default)
			)
			(layer "F.Fab")
		)
		(fp_line
			(start 0.120396 0.2794)
			(end -0.12065 0.2794)
			(stroke
				(width 0.1)
				(type default)
			)
			(layer "F.Fab")
		)
		(fp_line
			(start -0.12065 0.2794)
			(end -0.12065 0.3048)
			(stroke
				(width 0.1)
				(type default)
			)
			(layer "F.Fab")
		)
		(fp_line
			(start 0.67945 0.3048)
			(end 0.120396 0.3048)
			(stroke
				(width 0.1)
				(type default)
			)
			(layer "F.Fab")
		)
		(fp_line
			(start 0.120396 0.3048)
			(end 0.120396 0.2794)
			(stroke
				(width 0.1)
				(type default)
			)
			(layer "F.Fab")
		)
		(fp_line
			(start -0.12065 0.3048)
			(end -0.67945 0.3048)
			(stroke
				(width 0.1)
				(type default)
			)
			(layer "F.Fab")
		)
		(fp_line
			(start -0.67945 0.3048)
			(end -0.67945 -0.305054)
			(stroke
				(width 0.1)
				(type default)
			)
			(layer "F.Fab")
		)
		(pad "1" smd circle
			(at -0.40005 0 90)
			(size 0 0)
			(layers "F.Cu" "F.Mask" "F.Paste")
			(net "P3V3_AUX")
		)
		(pad "2" smd circle
			(at 0.40005 0 90)
			(size 0 0)
			(layers "F.Cu" "F.Mask" "F.Paste")
			(net "FAN_3_FAIL_R_LED")
		)
	)
	(footprint ""
		(layer "F.Cu")
		(at 18.288 -118.364 90)
		(property "Reference" "R5313"
			(at 0 0 90)
			(layer "F.SilkS")
			(hide yes)
			(effects
				(font
					(size 1.27 1.27)
				)
			)
		)
		(property "Value" ""
			(at 0 0 90)
			(layer "F.Fab")
			(effects
				(font
					(size 1.27 1.27)
				)
			)
		)
		(duplicate_pad_numbers_are_jumpers no)
		(fp_line
			(start 1.2954 -0.5842)
			(end 1.2954 0.5842)
			(stroke
				(width 0.1524)
				(type default)
			)
			(layer "F.SilkS")
		)
		(fp_line
			(start -1.2954 -0.5842)
			(end 1.2954 -0.5842)
			(stroke
				(width 0.1524)
				(type default)
			)
			(layer "F.SilkS")
		)
		(fp_line
			(start 1.2954 0.5842)
			(end -1.2954 0.5842)
			(stroke
				(width 0.1524)
				(type default)
			)
			(layer "F.SilkS")
		)
		(fp_line
			(start -1.2954 0.5842)
			(end -1.2954 -0.5842)
			(stroke
				(width 0.1524)
				(type default)
			)
			(layer "F.SilkS")
		)
		(fp_line
			(start 0.8636 -0.4572)
			(end 0.8636 -0.406654)
			(stroke
				(width 0.1)
				(type default)
			)
			(layer "F.Fab")
		)
		(fp_line
			(start -0.8636 -0.4572)
			(end 0.8636 -0.4572)
			(stroke
				(width 0.1)
				(type default)
			)
			(layer "F.Fab")
		)
		(fp_line
			(start 1.1938 -0.406654)
			(end 1.1938 0.4064)
			(stroke
				(width 0.1)
				(type default)
			)
			(layer "F.Fab")
		)
		(fp_line
			(start 0.8636 -0.406654)
			(end 1.1938 -0.406654)
			(stroke
				(width 0.1)
				(type default)
			)
			(layer "F.Fab")
		)
		(fp_line
			(start -0.8636 -0.406654)
			(end -0.8636 -0.4572)
			(stroke
				(width 0.1)
				(type default)
			)
			(layer "F.Fab")
		)
		(fp_line
			(start -1.1938 -0.406654)
			(end -0.8636 -0.406654)
			(stroke
				(width 0.1)
				(type default)
			)
			(layer "F.Fab")
		)
		(fp_line
			(start 1.1938 0.4064)
			(end 0.8636 0.4064)
			(stroke
				(width 0.1)
				(type default)
			)
			(layer "F.Fab")
		)
		(fp_line
			(start 0.8636 0.4064)
			(end 0.8636 0.4572)
			(stroke
				(width 0.1)
				(type default)
			)
			(layer "F.Fab")
		)
		(fp_line
			(start -0.8636 0.4064)
			(end -1.1938 0.4064)
			(stroke
				(width 0.1)
				(type default)
			)
			(layer "F.Fab")
		)
		(fp_line
			(start -1.1938 0.4064)
			(end -1.1938 -0.406654)
			(stroke
				(width 0.1)
				(type default)
			)
			(layer "F.Fab")
		)
		(fp_line
			(start -0.8636 0.4318)
			(end -0.8636 0.4064)
			(stroke
				(width 0.1)
				(type default)
			)
			(layer "F.Fab")
		)
		(fp_line
			(start 0.8636 0.4572)
			(end -0.8636 0.4572)
			(stroke
				(width 0.1)
				(type default)
			)
			(layer "F.Fab")
		)
		(fp_line
			(start -0.8636 0.4572)
			(end -0.8636 0.4318)
			(stroke
				(width 0.1)
				(type default)
			)
			(layer "F.Fab")
		)
		(pad "1" smd rect
			(at -0.7366 0)
			(size 0.7112 0.8128)
			(layers "F.Cu" "F.Mask" "F.Paste")
			(net "P52V_FAN_5")
		)
		(pad "2" smd rect
			(at 0.7366 0)
			(size 0.7112 0.8128)
			(layers "F.Cu" "F.Mask" "F.Paste")
			(net "FAN_5_TACH_OL_R")
		)
	)
	(footprint ""
		(layer "F.Cu")
		(at 12.954 -73.406 180)
		(property "Reference" "PR55"
			(at 0 0 180)
			(layer "F.SilkS")
			(hide yes)
			(effects
				(font
					(size 1.27 1.27)
				)
			)
		)
		(property "Value" ""
			(at 0 0 180)
			(layer "F.Fab")
			(effects
				(font
					(size 1.27 1.27)
				)
			)
		)
		(duplicate_pad_numbers_are_jumpers no)
		(fp_line
			(start 0.7874 0.4064)
			(end -0.7874 0.4064)
			(stroke
				(width 0.1524)
				(type default)
			)
			(layer "F.SilkS")
		)
		(fp_line
			(start 0.7874 -0.4064)
			(end 0.7874 0.4064)
			(stroke
				(width 0.1524)
				(type default)
			)
			(layer "F.SilkS")
		)
		(fp_line
			(start -0.7874 0.4064)
			(end -0.7874 -0.4064)
			(stroke
				(width 0.1524)
				(type default)
			)
			(layer "F.SilkS")
		)
		(fp_line
			(start -0.7874 -0.4064)
			(end 0.7874 -0.4064)
			(stroke
				(width 0.1524)
				(type default)
			)
			(layer "F.SilkS")
		)
		(fp_line
			(start 0.67945 0.3048)
			(end 0.120396 0.3048)
			(stroke
				(width 0.1)
				(type default)
			)
			(layer "F.Fab")
		)
		(fp_line
			(start 0.67945 -0.3048)
			(end 0.67945 0.3048)
			(stroke
				(width 0.1)
				(type default)
			)
			(layer "F.Fab")
		)
		(fp_line
			(start 0.12065 -0.2794)
			(end 0.12065 -0.3048)
			(stroke
				(width 0.1)
				(type default)
			)
			(layer "F.Fab")
		)
		(fp_line
			(start 0.12065 -0.3048)
			(end 0.67945 -0.3048)
			(stroke
				(width 0.1)
				(type default)
			)
			(layer "F.Fab")
		)
		(fp_line
			(start 0.120396 0.3048)
			(end 0.120396 0.2794)
			(stroke
				(width 0.1)
				(type default)
			)
			(layer "F.Fab")
		)
		(fp_line
			(start 0.120396 0.2794)
			(end -0.12065 0.2794)
			(stroke
				(width 0.1)
				(type default)
			)
			(layer "F.Fab")
		)
		(fp_line
			(start -0.12065 0.3048)
			(end -0.67945 0.3048)
			(stroke
				(width 0.1)
				(type default)
			)
			(layer "F.Fab")
		)
		(fp_line
			(start -0.12065 0.2794)
			(end -0.12065 0.3048)
			(stroke
				(width 0.1)
				(type default)
			)
			(layer "F.Fab")
		)
		(fp_line
			(start -0.12065 -0.2794)
			(end 0.12065 -0.2794)
			(stroke
				(width 0.1)
				(type default)
			)
			(layer "F.Fab")
		)
		(fp_line
			(start -0.12065 -0.305054)
			(end -0.12065 -0.2794)
			(stroke
				(width 0.1)
				(type default)
			)
			(layer "F.Fab")
		)
		(fp_line
			(start -0.67945 0.3048)
			(end -0.67945 -0.305054)
			(stroke
				(width 0.1)
				(type default)
			)
			(layer "F.Fab")
		)
		(fp_line
			(start -0.67945 -0.305054)
			(end -0.12065 -0.305054)
			(stroke
				(width 0.1)
				(type default)
			)
			(layer "F.Fab")
		)
		(pad "1" smd circle
			(at -0.40005 0 180)
			(size 0 0)
			(layers "F.Cu" "F.Mask" "F.Paste")
			(net "FAN_5_FAULT_R")
		)
		(pad "2" smd circle
			(at 0.40005 0 180)
			(size 0 0)
			(layers "F.Cu" "F.Mask" "F.Paste")
			(net "FAN_5_P3V_R")
		)
	)
)
